(kicad_pcb
	(version 20241229)
	(generator "pcbnew")
	(generator_version "9.0")
	(general
		(thickness 1.63)
		(legacy_teardrops no)
	)
	(paper "A4")
	(title_block
		(title "CM4 Baseboard")
		(date "2026-01-05")
		(rev "1.1.1")
		(company "Antmicro Ltd")
		(comment 1 "www.antmicro.com")
		(comment 9 "footprints 180-185 of 506")
	)
	(layers
		(0 "F.Cu" signal)
		(4 "In1.Cu" power)
		(6 "In2.Cu" power)
		(8 "In3.Cu" signal)
		(10 "In4.Cu" signal)
		(2 "B.Cu" signal)
		(9 "F.Adhes" user "F.Adhesive")
		(11 "B.Adhes" user "B.Adhesive")
		(13 "F.Paste" user)
		(15 "B.Paste" user)
		(5 "F.SilkS" user "F.Silkscreen")
		(7 "B.SilkS" user "B.Silkscreen")
		(1 "F.Mask" user)
		(3 "B.Mask" user)
		(17 "Dwgs.User" user "User.Drawings")
		(19 "Cmts.User" user "User.Comments")
		(21 "Eco1.User" user "User.Eco1")
		(23 "Eco2.User" user "User.Eco2")
		(25 "Edge.Cuts" user)
		(27 "Margin" user)
		(31 "F.CrtYd" user "F.Courtyard")
		(29 "B.CrtYd" user "B.Courtyard")
		(35 "F.Fab" user)
		(33 "B.Fab" user)
	)
	(footprint "antmicro-footprints:TSOT23-6"
		(layer "F.Cu")
		(at 96.712292 127.0165)
		(property "Reference" "U901"
			(at -2.062292 2.1335 90)
			(layer "F.SilkS")
			(effects
				(font
					(size 0.7 0.7)
					(thickness 0.15)
				)
				(justify left bottom)
			)
		)
		(property "Value" "AP22615A_TSOT26"
			(at 0 2.6 0)
			(layer "F.Fab")
			(effects
				(font
					(size 0.7 0.7)
					(thickness 0.15)
				)
				(justify left bottom)
			)
		)
		(property "Datasheet" "https://www.mouser.com/datasheet/2/115/DIOD_S_A0008958405_1-2543193.pdf"
			(at 0 0 0)
			(layer "F.Fab")
			(hide yes)
			(effects
				(font
					(size 1.27 1.27)
					(thickness 0.15)
				)
			)
		)
		(property "MPN" "AP22615AWU-7"
			(at 0 0 0)
			(unlocked yes)
			(layer "F.Fab")
			(hide yes)
			(effects
				(font
					(size 1 1)
					(thickness 0.15)
				)
			)
		)
		(property "Manufacturer" "Diodes Incorporated"
			(at 0 0 0)
			(unlocked yes)
			(layer "F.Fab")
			(hide yes)
			(effects
				(font
					(size 1 1)
					(thickness 0.15)
				)
			)
		)
		(property "Author" "Antmicro"
			(at 0 0 0)
			(unlocked yes)
			(layer "F.Fab")
			(hide yes)
			(effects
				(font
					(size 1 1)
					(thickness 0.15)
				)
			)
		)
		(property "License" "Apache-2.0"
			(at 0 0 0)
			(unlocked yes)
			(layer "F.Fab")
			(hide yes)
			(effects
				(font
					(size 1 1)
					(thickness 0.15)
				)
			)
		)
		(sheetname "/USB/")
		(sheetfile "usb.kicad_sch")
		(attr smd)
		(fp_line
			(start -1 -1.5)
			(end -1 -1.375)
			(stroke
				(width 0.15)
				(type solid)
			)
			(layer "F.SilkS")
		)
		(fp_line
			(start -1 1.55)
			(end -1 1.4)
			(stroke
				(width 0.15)
				(type solid)
			)
			(layer "F.SilkS")
		)
		(fp_line
			(start 1 -1.497)
			(end -1 -1.5)
			(stroke
				(width 0.15)
				(type solid)
			)
			(layer "F.SilkS")
		)
		(fp_line
			(start 1 -1.497)
			(end 1 -1.375)
			(stroke
				(width 0.15)
				(type solid)
			)
			(layer "F.SilkS")
		)
		(fp_line
			(start 1 1.55)
			(end -1 1.55)
			(stroke
				(width 0.15)
				(type solid)
			)
			(layer "F.SilkS")
		)
		(fp_line
			(start 1 1.55)
			(end 1 1.4)
			(stroke
				(width 0.15)
				(type solid)
			)
			(layer "F.SilkS")
		)
		(fp_circle
			(center -1.44 -1.5)
			(end -1.39 -1.5)
			(stroke
				(width 0.15)
				(type solid)
			)
			(fill yes)
			(layer "F.SilkS")
		)
		(fp_rect
			(start 1.93 -1.7)
			(end -1.93 1.7)
			(stroke
				(width 0.05)
				(type solid)
			)
			(fill no)
			(layer "F.CrtYd")
		)
		(fp_line
			(start -0.45 -1.521)
			(end -0.876 -1.096)
			(stroke
				(width 0.15)
				(type solid)
			)
			(layer "F.Fab")
		)
		(fp_rect
			(start 0.875 1.528)
			(end -0.875 -1.525)
			(stroke
				(width 0.15)
				(type solid)
			)
			(fill no)
			(layer "F.Fab")
		)
		(fp_text user "License: Apache-2.0"
			(at -1.93 6.199 0)
			(layer "F.Fab")
			(effects
				(font
					(size 0.7 0.7)
					(thickness 0.15)
				)
				(justify left bottom)
			)
		)
		(fp_text user "${REFERENCE}"
			(at -1.93 3.8 0)
			(layer "F.Fab")
			(effects
				(font
					(size 0.7 0.7)
					(thickness 0.15)
				)
				(justify left bottom)
			)
		)
		(fp_text user "Author: Antmicro"
			(at -1.93 5 0)
			(layer "F.Fab")
			(effects
				(font
					(size 0.7 0.7)
					(thickness 0.15)
				)
				(justify left bottom)
			)
		)
		(pad "1" smd rect
			(at -1.301 -0.947 270)
			(size 0.7 1.2)
			(layers "F.Cu" "F.Mask" "F.Paste")
			(net 24 "/Compute module/USBA_VBUS")
			(pinfunction "OUT")
			(pintype "power_out")
		)
		(pad "2" smd rect
			(at -1.301 0.004 270)
			(size 0.7 1.2)
			(layers "F.Cu" "F.Mask" "F.Paste")
			(net 3 "GND")
			(pinfunction "GND")
			(pintype "power_in")
		)
		(pad "3" smd rect
			(at -1.301 0.954 270)
			(size 0.7 1.2)
			(layers "F.Cu" "F.Mask" "F.Paste")
			(net 405 "unconnected-(U901-FLG-Pad3)")
			(pinfunction "FLG")
			(pintype "output+no_connect")
		)
		(pad "4" smd rect
			(at 1.299 0.954 270)
			(size 0.7 1.2)
			(layers "F.Cu" "F.Mask" "F.Paste")
			(net 288 "/USB/USBA_OUT_EN")
			(pinfunction "EN")
			(pintype "input")
		)
		(pad "5" smd rect
			(at 1.299 0.004 270)
			(size 0.7 1.2)
			(layers "F.Cu" "F.Mask" "F.Paste")
			(net 376 "Net-(U901-ISET)")
			(pinfunction "ISET")
			(pintype "passive")
		)
		(pad "6" smd rect
			(at 1.299 -0.947 270)
			(size 0.7 1.2)
			(layers "F.Cu" "F.Mask" "F.Paste")
			(net 28 "/USB/+5V_{CAP}")
			(pinfunction "IN")
			(pintype "power_in")
		)
	)
	(footprint "antmicro-footprints:TP_SMD_0.75mm"
		(layer "F.Cu")
		(at 87.23 130.53 180)
		(property "Reference" "TP915"
			(at -1.03 3.62 0)
			(layer "F.SilkS")
			(effects
				(font
					(size 0.7 0.7)
					(thickness 0.15)
				)
				(justify right bottom)
			)
		)
		(property "Value" "TP_0.75mm_SMD"
			(at 0 1.2 0)
			(layer "F.Fab")
			(effects
				(font
					(size 0.7 0.7)
					(thickness 0.15)
				)
				(justify right bottom)
			)
		)
		(property "MPN" ""
			(at 0 0 180)
			(unlocked yes)
			(layer "F.Fab")
			(hide yes)
			(effects
				(font
					(size 1 1)
					(thickness 0.15)
				)
			)
		)
		(property "Manufacturer" ""
			(at 0 0 180)
			(unlocked yes)
			(layer "F.Fab")
			(hide yes)
			(effects
				(font
					(size 1 1)
					(thickness 0.15)
				)
			)
		)
		(property "Author" "Antmicro"
			(at 0 0 180)
			(unlocked yes)
			(layer "F.Fab")
			(hide yes)
			(effects
				(font
					(size 1 1)
					(thickness 0.15)
				)
			)
		)
		(property "License" "Apache-2.0"
			(at 0 0 180)
			(unlocked yes)
			(layer "F.Fab")
			(hide yes)
			(effects
				(font
					(size 1 1)
					(thickness 0.15)
				)
			)
		)
		(sheetname "/USB/")
		(sheetfile "usb.kicad_sch")
		(attr exclude_from_pos_files exclude_from_bom)
		(fp_circle
			(center 0 0)
			(end 0.475 0)
			(stroke
				(width 0.05)
				(type default)
			)
			(fill no)
			(layer "F.CrtYd")
		)
		(fp_text user "${REFERENCE}"
			(at -0.4 2.7 180)
			(layer "F.Fab")
			(effects
				(font
					(size 0.7 0.7)
					(thickness 0.15)
				)
				(justify left bottom)
			)
		)
		(fp_text user "License: Apache-2.0"
			(at -0.4 5.101 180)
			(layer "F.Fab")
			(effects
				(font
					(size 0.7 0.7)
					(thickness 0.15)
				)
				(justify left bottom)
			)
		)
		(fp_text user "Author: Antmicro"
			(at -0.4 3.901 180)
			(layer "F.Fab")
			(effects
				(font
					(size 0.7 0.7)
					(thickness 0.15)
				)
				(justify left bottom)
			)
		)
		(pad "1" smd circle
			(at 0 0 180)
			(size 0.75 0.75)
			(layers "F.Cu" "F.Mask")
			(net 440 "Net-(U905-PD2_CC2)")
			(pinfunction "1")
			(pintype "passive")
		)
	)
	(footprint "antmicro-footprints:R_0402_1005Metric"
		(layer "F.Cu")
		(at 123.805476 163.6665)
		(descr "Resistor SMD 0402")
		(tags "resistor SMD 0402")
		(property "Reference" "R506"
			(at -3.837514 0.53 0)
			(layer "F.SilkS")
			(effects
				(font
					(size 0.7 0.7)
					(thickness 0.15)
				)
				(justify left bottom)
			)
		)
		(property "Value" "R_10k_0402"
			(at -1.011843 1.772047 0)
			(layer "F.Fab")
			(effects
				(font
					(size 0.7 0.7)
					(thickness 0.15)
				)
				(justify left bottom)
			)
		)
		(property "Datasheet" "https://www.bourns.com/docs/product-datasheets/cr.pdf"
			(at 0 0 0)
			(layer "F.Fab")
			(hide yes)
			(effects
				(font
					(size 1.27 1.27)
					(thickness 0.15)
				)
			)
		)
		(property "Manufacturer" "Bourns"
			(at 0 0 0)
			(unlocked yes)
			(layer "F.Fab")
			(hide yes)
			(effects
				(font
					(size 1 1)
					(thickness 0.15)
				)
			)
		)
		(property "MPN" "CR0402-FX-1002GLF"
			(at 0 0 0)
			(unlocked yes)
			(layer "F.Fab")
			(hide yes)
			(effects
				(font
					(size 1 1)
					(thickness 0.15)
				)
			)
		)
		(property "Val" "10k"
			(at 0 0 0)
			(unlocked yes)
			(layer "F.Fab")
			(hide yes)
			(effects
				(font
					(size 1 1)
					(thickness 0.15)
				)
			)
		)
		(property "License" "Apache-2.0"
			(at 0 0 0)
			(unlocked yes)
			(layer "F.Fab")
			(hide yes)
			(effects
				(font
					(size 1 1)
					(thickness 0.15)
				)
			)
		)
		(property "Author" "Antmicro"
			(at 0 0 0)
			(unlocked yes)
			(layer "F.Fab")
			(hide yes)
			(effects
				(font
					(size 1 1)
					(thickness 0.15)
				)
			)
		)
		(property "Tolerance" "1%"
			(at 0 0 0)
			(unlocked yes)
			(layer "F.Fab")
			(hide yes)
			(effects
				(font
					(size 1 1)
					(thickness 0.15)
				)
			)
		)
		(sheetname "/NVMe & microSD/")
		(sheetfile "nvme-micro-sd.kicad_sch")
		(attr smd)
		(fp_rect
			(start -0.925 -0.47)
			(end 0.925 0.47)
			(stroke
				(width 0.05)
				(type default)
			)
			(fill no)
			(layer "F.CrtYd")
		)
		(fp_rect
			(start -0.5 -0.25)
			(end 0.5 0.25)
			(stroke
				(width 0.15)
				(type solid)
			)
			(fill no)
			(layer "F.Fab")
		)
		(fp_text user "Author: Antmicro"
			(at -0.95 4.169 0)
			(layer "F.Fab")
			(effects
				(font
					(size 0.7 0.7)
					(thickness 0.15)
				)
				(justify left bottom)
			)
		)
		(fp_text user "${REFERENCE}"
			(at -0.95 3.168 0)
			(layer "F.Fab")
			(effects
				(font
					(size 0.7 0.7)
					(thickness 0.15)
				)
				(justify left bottom)
			)
		)
		(fp_text user "License: Apache-2.0"
			(at -0.95 5.169 0)
			(layer "F.Fab")
			(effects
				(font
					(size 0.7 0.7)
					(thickness 0.15)
				)
				(justify left bottom)
			)
		)
		(pad "1" smd roundrect
			(at -0.48 0)
			(size 0.59 0.64)
			(layers "F.Cu" "F.Mask" "F.Paste")
			(roundrect_rratio 0.25)
			(net 9 "+3V3")
			(pintype "passive")
		)
		(pad "2" smd roundrect
			(at 0.48 0)
			(size 0.59 0.64)
			(layers "F.Cu" "F.Mask" "F.Paste")
			(roundrect_rratio 0.25)
			(net 6 "/Compute module/SDIO.D0")
			(pintype "passive")
		)
	)
	(footprint "antmicro-footprints:XDFN-2_1x0.60mm"
		(layer "F.Cu")
		(at 132.367962 126.3915 180)
		(property "Reference" "D204"
			(at -0.89 -1.385 0)
			(layer "F.SilkS")
			(effects
				(font
					(size 0.7 0.7)
					(thickness 0.15)
				)
				(justify right bottom)
			)
		)
		(property "Value" "TPD1E0B04_XDFN-2"
			(at 0 1.5 0)
			(layer "F.Fab")
			(effects
				(font
					(size 0.7 0.7)
					(thickness 0.15)
				)
				(justify right bottom)
			)
		)
		(property "Datasheet" "https://www.ti.com/general/docs/suppproductinfo.tsp?distId=26&gotoUrl=https://www.ti.com/lit/gpn/tpd1e0b04"
			(at 0 0 180)
			(layer "F.Fab")
			(hide yes)
			(effects
				(font
					(size 1.27 1.27)
					(thickness 0.15)
				)
			)
		)
		(property "MPN" "TPD1E0B04DPYR"
			(at 264.735924 252.783 0)
			(layer "F.Fab")
			(hide yes)
			(effects
				(font
					(size 1 1)
					(thickness 0.15)
				)
			)
		)
		(property "Manufacturer" "Texas Instruments"
			(at 264.735924 252.783 0)
			(layer "F.Fab")
			(hide yes)
			(effects
				(font
					(size 1 1)
					(thickness 0.15)
				)
			)
		)
		(property "Author" "Antmicro"
			(at 0 0 180)
			(unlocked yes)
			(layer "F.Fab")
			(hide yes)
			(effects
				(font
					(size 1 1)
					(thickness 0.15)
				)
			)
		)
		(property "License" "Apache-2.0"
			(at 0 0 180)
			(unlocked yes)
			(layer "F.Fab")
			(hide yes)
			(effects
				(font
					(size 1 1)
					(thickness 0.15)
				)
			)
		)
		(sheetname "/Compute module/")
		(sheetfile "compute-module.kicad_sch")
		(attr smd)
		(fp_rect
			(start -0.725 -0.475)
			(end 0.725 0.475)
			(stroke
				(width 0.05)
				(type solid)
			)
			(fill no)
			(layer "F.CrtYd")
		)
		(fp_rect
			(start -0.55 -0.35)
			(end 0.55 0.35)
			(stroke
				(width 0.15)
				(type solid)
			)
			(fill no)
			(layer "F.Fab")
		)
		(fp_text user "${REFERENCE}"
			(at -0.8 3.2 180)
			(layer "F.Fab")
			(effects
				(font
					(size 0.7 0.7)
					(thickness 0.15)
				)
				(justify left bottom)
			)
		)
		(fp_text user "Author: Antmicro"
			(at -0.8 4.4 180)
			(layer "F.Fab")
			(effects
				(font
					(size 0.7 0.7)
					(thickness 0.15)
				)
				(justify left bottom)
			)
		)
		(fp_text user "License: Apache-2.0"
			(at -0.8 5.6 180)
			(layer "F.Fab")
			(effects
				(font
					(size 0.7 0.7)
					(thickness 0.15)
				)
				(justify left bottom)
			)
		)
		(pad "1" smd roundrect
			(at -0.351 0 180)
			(size 0.3 0.5)
			(layers "F.Cu" "F.Mask" "F.Paste")
			(roundrect_rratio 0.25)
			(net 3 "GND")
			(pinfunction "C")
			(pintype "passive")
		)
		(pad "2" smd roundrect
			(at 0.349 0 180)
			(size 0.3 0.5)
			(layers "F.Cu" "F.Mask" "F.Paste")
			(roundrect_rratio 0.25)
			(net 4 "Net-(D204-A)")
			(pinfunction "A")
			(pintype "passive")
		)
	)
	(footprint "antmicro-footprints:R_0402_1005Metric"
		(layer "F.Cu")
		(at 75.242962 132.1915)
		(descr "Resistor SMD 0402")
		(tags "resistor SMD 0402")
		(property "Reference" "R921"
			(at -7.592962 2.3585 0)
			(layer "F.SilkS")
			(effects
				(font
					(size 0.7 0.7)
					(thickness 0.15)
				)
				(justify left bottom)
			)
		)
		(property "Value" "R_470R_0402"
			(at -1.011843 1.772047 0)
			(layer "F.Fab")
			(effects
				(font
					(size 0.7 0.7)
					(thickness 0.15)
				)
				(justify left bottom)
			)
		)
		(property "Datasheet" "https://www.bourns.com/docs/product-datasheets/cr.pdf"
			(at 0 0 0)
			(layer "F.Fab")
			(hide yes)
			(effects
				(font
					(size 1.27 1.27)
					(thickness 0.15)
				)
			)
		)
		(property "MPN" "CR0402-FX-4700GLF"
			(at 0 0 0)
			(unlocked yes)
			(layer "F.Fab")
			(hide yes)
			(effects
				(font
					(size 1 1)
					(thickness 0.15)
				)
			)
		)
		(property "Manufacturer" "Bourns"
			(at 0 0 0)
			(unlocked yes)
			(layer "F.Fab")
			(hide yes)
			(effects
				(font
					(size 1 1)
					(thickness 0.15)
				)
			)
		)
		(property "License" "Apache-2.0"
			(at 0 0 0)
			(unlocked yes)
			(layer "F.Fab")
			(hide yes)
			(effects
				(font
					(size 1 1)
					(thickness 0.15)
				)
			)
		)
		(property "Author" "Antmicro"
			(at 0 0 0)
			(unlocked yes)
			(layer "F.Fab")
			(hide yes)
			(effects
				(font
					(size 1 1)
					(thickness 0.15)
				)
			)
		)
		(property "Val" "470R"
			(at 0 0 0)
			(unlocked yes)
			(layer "F.Fab")
			(hide yes)
			(effects
				(font
					(size 1 1)
					(thickness 0.15)
				)
			)
		)
		(property "Tolerance" "1%"
			(at 0 0 0)
			(unlocked yes)
			(layer "F.Fab")
			(hide yes)
			(effects
				(font
					(size 1 1)
					(thickness 0.15)
				)
			)
		)
		(sheetname "/USB/")
		(sheetfile "usb.kicad_sch")
		(attr smd)
		(fp_rect
			(start -0.925 -0.47)
			(end 0.925 0.47)
			(stroke
				(width 0.05)
				(type default)
			)
			(fill no)
			(layer "F.CrtYd")
		)
		(fp_rect
			(start -0.5 -0.25)
			(end 0.5 0.25)
			(stroke
				(width 0.15)
				(type solid)
			)
			(fill no)
			(layer "F.Fab")
		)
		(fp_text user "Author: Antmicro"
			(at -0.95 4.169 0)
			(layer "F.Fab")
			(effects
				(font
					(size 0.7 0.7)
					(thickness 0.15)
				)
				(justify left bottom)
			)
		)
		(fp_text user "License: Apache-2.0"
			(at -0.95 5.169 0)
			(layer "F.Fab")
			(effects
				(font
					(size 0.7 0.7)
					(thickness 0.15)
				)
				(justify left bottom)
			)
		)
		(fp_text user "${REFERENCE}"
			(at -0.95 3.168 0)
			(layer "F.Fab")
			(effects
				(font
					(size 0.7 0.7)
					(thickness 0.15)
				)
				(justify left bottom)
			)
		)
		(pad "1" smd roundrect
			(at -0.48 0)
			(size 0.59 0.64)
			(layers "F.Cu" "F.Mask" "F.Paste")
			(roundrect_rratio 0.25)
			(net 489 "Net-(D912-A)")
			(pintype "passive")
		)
		(pad "2" smd roundrect
			(at 0.48 0)
			(size 0.59 0.64)
			(layers "F.Cu" "F.Mask" "F.Paste")
			(roundrect_rratio 0.25)
			(net 27 "/USB/USB_3V3")
			(pintype "passive")
		)
	)
	(footprint "antmicro-footprints:R_0402_1005Metric"
		(layer "F.Cu")
		(at 101.167962 132.9415)
		(descr "Resistor SMD 0402")
		(tags "resistor SMD 0402")
		(property "Reference" "R928"
			(at 0.905 0.45 0)
			(layer "F.SilkS")
			(effects
				(font
					(size 0.7 0.7)
					(thickness 0.15)
				)
				(justify left bottom)
			)
		)
		(property "Value" "R_10k_0402"
			(at -1.011843 1.772047 0)
			(layer "F.Fab")
			(effects
				(font
					(size 0.7 0.7)
					(thickness 0.15)
				)
				(justify left bottom)
			)
		)
		(property "Datasheet" "https://www.bourns.com/docs/product-datasheets/cr.pdf"
			(at 0 0 0)
			(layer "F.Fab")
			(hide yes)
			(effects
				(font
					(size 1.27 1.27)
					(thickness 0.15)
				)
			)
		)
		(property "Manufacturer" "Bourns"
			(at 0 0 0)
			(unlocked yes)
			(layer "F.Fab")
			(hide yes)
			(effects
				(font
					(size 1 1)
					(thickness 0.15)
				)
			)
		)
		(property "MPN" "CR0402-FX-1002GLF"
			(at 0 0 0)
			(unlocked yes)
			(layer "F.Fab")
			(hide yes)
			(effects
				(font
					(size 1 1)
					(thickness 0.15)
				)
			)
		)
		(property "Val" "10k"
			(at 0 0 0)
			(unlocked yes)
			(layer "F.Fab")
			(hide yes)
			(effects
				(font
					(size 1 1)
					(thickness 0.15)
				)
			)
		)
		(property "License" "Apache-2.0"
			(at 0 0 0)
			(unlocked yes)
			(layer "F.Fab")
			(hide yes)
			(effects
				(font
					(size 1 1)
					(thickness 0.15)
				)
			)
		)
		(property "Author" "Antmicro"
			(at 0 0 0)
			(unlocked yes)
			(layer "F.Fab")
			(hide yes)
			(effects
				(font
					(size 1 1)
					(thickness 0.15)
				)
			)
		)
		(property "Tolerance" "1%"
			(at 0 0 0)
			(unlocked yes)
			(layer "F.Fab")
			(hide yes)
			(effects
				(font
					(size 1 1)
					(thickness 0.15)
				)
			)
		)
		(sheetname "/USB/")
		(sheetfile "usb.kicad_sch")
		(attr smd)
		(fp_rect
			(start -0.925 -0.47)
			(end 0.925 0.47)
			(stroke
				(width 0.05)
				(type default)
			)
			(fill no)
			(layer "F.CrtYd")
		)
		(fp_rect
			(start -0.5 -0.25)
			(end 0.5 0.25)
			(stroke
				(width 0.15)
				(type solid)
			)
			(fill no)
			(layer "F.Fab")
		)
		(fp_text user "${REFERENCE}"
			(at -0.95 3.168 0)
			(layer "F.Fab")
			(effects
				(font
					(size 0.7 0.7)
					(thickness 0.15)
				)
				(justify left bottom)
			)
		)
		(fp_text user "Author: Antmicro"
			(at -0.95 4.169 0)
			(layer "F.Fab")
			(effects
				(font
					(size 0.7 0.7)
					(thickness 0.15)
				)
				(justify left bottom)
			)
		)
		(fp_text user "License: Apache-2.0"
			(at -0.95 5.169 0)
			(layer "F.Fab")
			(effects
				(font
					(size 0.7 0.7)
					(thickness 0.15)
				)
				(justify left bottom)
			)
		)
		(pad "1" smd roundrect
			(at -0.48 0)
			(size 0.59 0.64)
			(layers "F.Cu" "F.Mask" "F.Paste")
			(roundrect_rratio 0.25)
			(net 127 "Net-(Q903-G)")
			(pintype "passive")
		)
		(pad "2" smd roundrect
			(at 0.48 0)
			(size 0.59 0.64)
			(layers "F.Cu" "F.Mask" "F.Paste")
			(roundrect_rratio 0.25)
			(net 10 "+5V")
			(pintype "passive")
		)
	)
)
